# Lightning_FCB_BOM.xlsx — Lightning FCB BOM (bom)
| Level | Parent Number | Part Number | Description | Green Factor | Life Cycle State | Manufacturer | Manufacturer Part Number | Source | BOM Usage | M/P Code | S/D | Qty | UoM | Location |
| 1 | 91.64W10.A57G | 038.02001.0081 | SOLDER PASTE PF606-P (TYPE 4:20~38UM) | R2_SA; | Released | SHENMAO | P0606X409504200 | Single |  | Purchase |  | 1.79 | PCS |  |
| 1 | 91.64W10.A57G | 038.02001.0091 | SOLDER BAR PF529-B | R2_SA;HF_SA; | Released | SHENMAO | B1529X10KX413 | Single |  | Purchase |  | 1.53 | PCS |  |
| 1 | 91.64W10.A57G | 038.02001.0101 | SOLDER BAR PF530-B | R2_SA;HF_SA; | Released | SHENMAO | B2530X25KX413 | Single |  | Purchase |  | 2.1800000000000002 | PCS |  |
| 1 | 91.64W10.A57G | 55.64W02.A91G | KNOX FCB(DIP) | R2; | Released |  |  |  | M | Manufacture |  | 1 | PCS |  |
| 2 | 55.64W02.A91G | 006.01149.0140 | LED RED/BLUE LTL1BETBEMKH149 | R2_SA;HF_SA; | Released | LITEON | LTL1BETBEMKH149 | Single |  | Purchase | DIP | 6 | PCS | LED1 LED2 LED3 LED4 LED5 LED6 |
| 2 | 55.64W02.A91G | 086.A9574.05R0 | SCRW M3L5 TAP PE WASHER | R2_SA;HF_SA; | Released | TBD |  | Single |  | Purchase | DIP | 12 | PCS |  |
| 2 | 55.64W02.A91G | 20.81943.024 | CONN CTR 4P+20S ST 51952-220LF ,PA66 | R2_SA; | Released | FCI | 51952-220LF | Multiple |  | Purchase | DIP | 2 | PCS | CN10 CN9 |
| 2 | 55.64W02.A91G | 21.61427.105 | HEAD ML 1R5P RT A2541WR0-1TX5 ,NYLON6T | R2_SA;HF_SA; | Released | JWT | A2541WR0-1TX5PA-6T | Single |  | Purchase | DIP | 6 | PCS | CN1 CN2 CN3 CN4 CN5 CN6 |
| 2 | 55.64W02.A91G | 21.61942.103 | HAED ML 3P 21S-H91-03GB31 W/JUMPER G/F | R2_SA;HF_SA; | Released | PINREX | 21S-H91-03GB31 | Single |  | Purchase | DIP | 1 | PCS | JP1 |
| 2 | 55.64W02.A91G | 21.63033.103 | HEAD ML 1R3P ST 210-91-03GB01 ,PA9T | R2_SA; | Released | PINREX | 210-91-03GB01 | Multiple |  | Purchase | DIP | 1 | PCS | CN8 |
| 2 | 55.64W02.A91G | 40.58D03.001 | LBL POLYIMIDE31.8*6.35 BARCODE | R2_SA;HF_SA;G_SA; | Released | LABELJET | 40.58D03.001 | Single |  | Purchase | DIP | 2 | PCS |  |
| 2 | 55.64W02.A91G | 40.64W19.001 | LBL YELLOW KNOX 25.5X12.8MM FOR KNOX | R2_SA;HF_SA; | Released | TBD |  | Single |  | Purchase | DIP | 1 | PCS |  |
| 2 | 55.64W02.A91G | 42.64W15.001 | HLDR FAN CONN 1 HU230 | R2_SA;HF_SA; | Released | TBD |  | Single |  | Purchase | DIP | 6 | PCS |  |
| 2 | 55.64W02.A91G | 55.64W02.MAAG | KNOX FCB(SMT) | R2; | Released |  |  |  | M | Manufacture | DIP | 1 | PCS |  |
| 3 | 55.64W02.MAAG | 077.56861.0001 | CHIP CAP EL 68U 16V M7343 ESR40 | R2_SA;HF_SA; | Released | PANASONIC | EEFCX1C680R | Single |  | Purchase | SMT | 9 | PCS | TC1 TC10 TC11 TC2 TC3 TC5 TC6 TC7 TC9 |
| 3 | 55.64W02.MAAG | 084.00925.003N | FET MOS PH0925CL,115 NC LFPAK 4P | R2_SA;HF_SA; | Released | NXP | PH0925CL,115 | Multiple |  | Purchase | SMT | 8 | PCS | PQ1 PQ11 PQ12 PQ13 PQ2 PQ3 PQ7 PQ8 |
| 3 | 55.64W02.MAAG | 34.64W28.001 | BOSS NUT H1.2 M4 NON PB | R2_SA;HF_SA; | Released | TBD |  | Single |  | Purchase | SMT | 5 | PCS | H10 H11 H12 H13 H9 |
| 3 | 55.64W02.MAAG | 48.64W29.02A | PCB 12433-2A KNOX_FAN CONTROL BOARD 4L G | R2_SA; | Released | GCE |  | Multiple |  | Purchase | SMT | 1 | PCS | PCBL |
| 3 | 55.64W02.MAAG | 63.00000.00L | CHIP RES 0 J 1/10W 0603 | R2_SA;HF_SA;G_SA; | Released | TA-I ; RALEC ; YAGEO ; WALSIN | RM06JTN0 ; RTT03000JTP ; RC0603JR-070RL ; WR06X000PTL | Multiple |  | Purchase | SMT | 1 | PCS | PR54 |
| 3 | 55.64W02.MAAG | 63.10134.1DL | CHIP RES 100 J 1/16W 0402 | R2_SA;HF_SA;G_SA; | Released | TA-I;RALEC;CYNTEC;YAGEO;WALSIN | RM04JTN101 ; RTT02101JTH ; RR0510S-101-JN ; RC0402JR-07100RL;WR04X101JTL | Multiple |  | Purchase | SMT | 2 | PCS | R360 R361 |
| 3 | 55.64W02.MAAG | 63.10333.15L | CHIP RES 10K J 1/10W 0603 | R2_SA;HF_SA;G_SA; | Released | RALEC;TA-I;YAGEO;WALSIN | RTT03103JTP;RM06JTN103;RC0603JR-0710KL;WR06X103JTL | Multiple |  | Purchase | SMT | 1 | PCS | PR53 |
| 3 | 55.64W02.MAAG | 63.10434.1DL | CHIP RES 100K J 1/16W 0402 | R2_SA;HF_SA;G_SA; | Released | TA-I;RALEC;CYNTEC;YAGEO;WALSIN | RM04JTN104 ; RTT02104JTH ; RR0510S-104-JN ; RC0402JR-07100KL;WR04X104JTL | Multiple |  | Purchase | SMT | 1 | PCS | R11 |
| 3 | 55.64W02.MAAG | 63.10534.1DL | CHIP RES 1M J 1/16W 0402 | R2_SA;HF_SA;G_SA; | Released | TA-I;RALEC;CYNTEC;YAGEO;WALSIN | RM04JTN105 ; RTT02105JTH ; RR0510S-105-JN ; RC0402JR-071ML;WR04X105JTL | Multiple |  | Purchase | SMT | 1 | PCS | R10 |
| 3 | 55.64W02.MAAG | 63.10634.1DL | CHIP RES 10M J 1/16W 0402 | R2_SA;HF_SA;G_SA; | Released | TA-I;RALEC;CYNTEC;YAGEO;WALSIN | RM04JTN106 ; RTT02106JTH ; RR0510S-106-JN ; RC0402JR-0710ML;WR04X106JTL | Multiple |  | Purchase | SMT | 1 | PCS | R365 |
| 3 | 55.64W02.MAAG | 63.15231.16L | CHIP RES 1.5K J 1/8W 0805(ROHS | R2_SA;HF_SA;G_SA; | Released | TAI;YAGEO;RALEC | RM10JTN152;RC0805JR-071K5L;RTT05152JTP | Multiple |  | Purchase | SMT | 1 | PCS | PR43 |
| 3 | 55.64W02.MAAG | 63.18232.11L | CHIP RES 1.8K J 1/4W 1206 | R2_SA;HF_SA;G_SA; | Released | RALEC ; TA-I ; YAGEO | RTT06182JTP ; RM12JTN182 ; RC1206JR-071K8L | Multiple |  | Purchase | SMT | 6 | PCS | R122 R123 R124 R125 R126 R127 |
| 3 | 55.64W02.MAAG | 63.33134.1DL | CHIP RES 330 J 1/16W 0402 | R2_SA;HF_SA;G_SA; | Released | TA-I;RALEC;CYNTEC;YAGEO;WALSIN | RM04JTN331 ; RTT02331JTH ; RR0510S-331-JN ; RC0402JR-07330RL;WR04X331JTL | Multiple |  | Purchase | SMT | 6 | PCS | R129 R148 R149 R155 R156 R157 |
| 3 | 55.64W02.MAAG | 63.47234.1DL | CHIP RES 4.7K J 1/16W 0402 | R2_SA;HF_SA;G_SA; | Released | TA-I;RALEC;CYNTEC;YAGEO;WALSIN | RM04JTN472 ; RTT02472JTH ; RR0510S-472-JN ; RC0402JR-074K7L;WR04X472JTL | Multiple |  | Purchase | SMT | 8 | PCS | PR49 R39 R43 R44 R48 R54 R55 R56 |
| 3 | 55.64W02.MAAG | 63.R0031.16L | CHIP RES 0 J 1/8W 0805 | R2_SA;HF_SA;G_SA; | Released | TAI;RALEC;YAGEO;WALSIN | RM10JTN0 ; RTT05000JTP ; RC0805JR-070RL ; WR08X000PTL | Multiple |  | Purchase | SMT | 1 | PCS | R8 |
| 3 | 55.64W02.MAAG | 63.R0034.1DL | CHIP RES 0 J 1/16W 0402 | R2_SA;HF_SA;G_SA; | Released | TAI;RALEC;CYNTEC;YAGEO;WALSIN | RM04JTN0;RTT02000JTH;RR0510X-000-XN;RC0402JR-070RL;WR04X000PTL | Multiple |  | Purchase | SMT | 42 | PCS | PR14 PR94 PR95 PR96 PR97 R1 R106 R107 R108 R109 R136 R137 R138 R139 R140 R141 R164 R165 R171 R172 R173 R174 R175 R176 R183 R184 R2 R26 R28 R30 R32 R34 R364 R38 R4 R45 R46 R47 R5 R51 R62 R63 |
| 3 | 55.64W02.MAAG | 64.0U505.L0L | CHIP RES 0.0005 F 1W 0612 | R2_SA;HF_SA; | Released | VISHAY;CYNTEC | WSK0612L5000FEA;RL1632L4-0R5M-FN | Multiple |  | Purchase | SMT | 3 | PCS | PR29 PR30 PR31 |
| 3 | 55.64W02.MAAG | 64.10005.6DL | CHIP RES 100 F 1/16W 0402 | R2_SA;HF_SA;G_SA; | Released | TA-I ; RALEC ; CYNTEC ; YAGEO;WALSIN | RM04FTN1000 ; RTT021000FTH ; RR0510S-1000-FN ; RC0402FR-07100RL;WR04X1000FTL | Multiple |  | Purchase | SMT | 2 | PCS | PR101 PR99 |
| 3 | 55.64W02.MAAG | 64.10015.6DL | CHIP RES 1K F 1/16W 0402 | R2_SA;HF_SA;G_SA; | Released | TA-I;RALEC;CYNTEC;YAGEO;WALSIN | RM04FTN1001 ; RTT021001FTH ; RR0510S-102-FN ; RC0402FR-071KL;WR04X1001FTL | Multiple |  | Purchase | SMT | 6 | PCS | PR106 PR107 PR16 PR38 PR41 PR7 |
| 3 | 55.64W02.MAAG | 64.10025.6DL | CHIP RES 10K F 1/16W 0402 | R2_SA;HF_SA;G_SA; | Released | TA-I;RALEC;CYNTEC;YAGEO;WALSIN | RM04FTN1002 ; RTT021002FTH ; RR0510S-103-FN ; RC0402FR-0710KL;WR04X1002FTL | Multiple |  | Purchase | SMT | 19 | PCS | PR58 R102 R103 R104 R105 R128 R15 R35 R359 R366 R367 R74 R75 R76 R77 R88 R89 R90 R91 |
| 3 | 55.64W02.MAAG | 64.10035.6DL | CHIP RES 100K F 1/16W 0402 | R2_SA;HF_SA;G_SA; | Released | TA-I;RALEC;CYNTEC;YAGEO;WALSIN | RM04FTN1003 ; RTT021003FTH ; RR0510S-104-FN ; RC0402FR-07100KL;WR04X1003FTL | Multiple |  | Purchase | SMT | 7 | PCS | PR1 PR55 PR6 R17 R18 R19 R21 |
| 3 | 55.64W02.MAAG | 64.10R05.6DL | CHIP RES 10 F 1/16W 0402 | R2_SA;HF_SA;G_SA; | Released | TAI;RALEC;CYNTEC;YAGEO;WALSIN | RM04FTN10R0;RTT0210R0FTH;RR0510S-100-FN;RC0402FR-0710RL;WR04X10R0FTL | Multiple |  | Purchase | SMT | 17 | PCS | PR102 PR103 PR118 PR119 PR18 PR19 PR2 PR20 PR21 PR22 PR23 PR26 PR27 PR28 PR51 R150 R151 |
| 3 | 55.64W02.MAAG | 64.11025.6DL | CHIP RES 11K F 1/16W 0402 | R2_SA;HF_SA;G_SA; | Released | TA-I ; RALEC ; CYNTEC ; YAGEO;WALSIN | RM04FTN1102 ; RTT021102FTH ; RR0510S-1102-FN ; RC0402FR-0711KL;WR04X1102FTL | Multiple |  | Purchase | SMT | 1 | PCS | PR8 |
| 3 | 55.64W02.MAAG | 64.11035.L0L | CHIP RES 110K F 1/16W 0402 | R2_SA;HF_SA;G_SA; | Released | TA-I;RALEC;CYNTEC | RM04FTN1103;RTT021103FTH;RR0510S-1103-FN | Multiple |  | Purchase | SMT | 3 | PCS | R14 R16 R36 |
| 3 | 55.64W02.MAAG | 64.17835.6DL | CHIP RES 178K F 1/16W 0402 | R2_SA;HF_SA;G_SA; | Released | TAI;RALEC;CYNTEC;YAGEO | RM04FTN1783;RTT021783FTH;RR0510S-1783-FN;RC0402FR-07178KL | Multiple |  | Purchase | SMT | 2 | PCS | PR110 PR111 |
| 3 | 55.64W02.MAAG | 64.20015.6DL | CHIP RES 2K F 1/16W 0402 | R2_SA;HF_SA;G_SA; | Released | TA-I;RALEC;CYNTEC;YAGEO;WALSIN | RM04FTN2001 ; RTT022001FTH ; RR0510S-202-FN ; RC0402FR-072KL;WR04X2001FTL | Multiple |  | Purchase | SMT | 6 | PCS | R111 R113 R115 R117 R119 R121 |
| 3 | 55.64W02.MAAG | 64.20025.6DL | CHIP RES 20K F 1/16W 0402 | R2_SA;HF_SA;G_SA; | Released | TA-I;RALEC;CYNTEC;YAGEO;WALSIN | RM04FTN2002 ; RTT022002FTH ; RR0510S-203-FN ; RC0402FR-0720KL;WR04X2002FTL | Multiple |  | Purchase | SMT | 2 | PCS | PR114 PR115 |
| 3 | 55.64W02.MAAG | 64.22125.55L | CHIP RES 22.1K F 1/10W 0603 | R2_SA;HF_SA;G_SA; | Released | TA-I ; RALEC ; YAGEO | RM06FTN2212 ; RTT032212FTP ; RC0603FR-0722K1L | Multiple |  | Purchase | SMT | 1 | PCS | PR56 |
| 3 | 55.64W02.MAAG | 64.27015.6DL | CHIP RES 2.7K F 1/16W 0402 | R2_SA;HF_SA;G_SA; | Released | TAI;RALEC;CYNTEC;YAGEO | RM04FTN2701;RTT022701FTH;RR0510S-2701-FN;RC0402FR-072K7L | Multiple |  | Purchase | SMT | 2 | PCS | PR104 PR105 |
| 3 | 55.64W02.MAAG | 64.27025.55L | CHIP RES 27K F 1/10W 0603 | R2_SA;HF_SA;G_SA; | Released | TA-I ; RALEC ; YAGEO | RM06FTN2702 ; RTT032702FTP ; RC0603FR-0727KL | Multiple |  | Purchase | SMT | 12 | PCS | R100 R101 R70 R71 R72 R73 R84 R85 R86 R87 R98 R99 |
| 3 | 55.64W02.MAAG | 64.40215.6DL | CHIP RES 4.02K F 1/16W 0402 | R2_SA;HF_SA;G_SA; | Released | TA-I;RALEC;CYNTEC;YAGEO;WALSIN | RM04FTN4021;RTT024021FTH;RR0510S-4021-FN;RC0402FR-074K02L;WR04X4021FTL | Multiple |  | Purchase | SMT | 1 | PCS | PR36 |
| 3 | 55.64W02.MAAG | 64.47005.6DL | CHIP RES 470 F 1/16W 0402 | R2_SA;HF_SA;G_SA; | Released | TA-I;RALEC;CYNTEC;YAGEO | RM04FTN4700;RTT024700FTH;RR0510S-471-FN;RC0402FR-07470RL | Multiple |  | Purchase | SMT | 4 | PCS | R114 R116 R118 R120 |
| 3 | 55.64W02.MAAG | 64.47015.6DL | CHIP RES 4.7K F 1/16W 0402 | R2_SA;HF_SA;G_SA; | Released | TA-I;RALEC;CYNTEC;YAGEO;WALSIN | RM04FTN4701;RTT024701FTH;RR0510S-472-FN;RC0402FR-074K7L;WR04X4701FTL | Multiple |  | Purchase | SMT | 25 | PCS | PR15 PR59 R12 R130 R131 R132 R133 R134 R135 R20 R3 R60 R61 R66 R67 R68 R69 R80 R81 R82 R83 R93 R94 R95 R97 |
| 3 | 55.64W02.MAAG | 64.47025.55L | CHIP RES 47K F 1/10W 0603 | R2_SA;HF_SA;G_SA; | Released | TA-I ; RALEC ; YAGEO | RM06FTN4702 ; RTT034702FTP ; RC0603FR-0747KL | Multiple |  | Purchase | SMT | 1 | PCS | PR52 |
| 3 | 55.64W02.MAAG | 64.49915.6DL | CHIP RES 4.99K F 1/16W 0402 | R2_SA;HF_SA;G_SA; | Released | TA-I;RALEC;CYNTEC;YAGEO;WALSIN | RM04FTN4991 ; RTT024991FTH ; RR0510S-4991-FN ; RC0402FR-074K99L ; WR04X4991FTL | Multiple |  | Purchase | SMT | 1 | PCS | PR37 |
| 3 | 55.64W02.MAAG | 64.49925.6DL | CHIP RES 49.9K F 1/16W 0402 | R2_SA;HF_SA;G_SA; | Released | TA-I ; RALEC ; CYNTEC ; YAGEO ; WALSIN | RM04FTN4992 ; RTT024992FTH ; RR0510S-4992-FN ; RC0402FR-0749K9L ; WR04X4992FTL | Multiple |  | Purchase | SMT | 1 | PCS | PR4 |
| 3 | 55.64W02.MAAG | 64.51015.6DL | CHIP RES 5.1K F 1/16W 0402 | R2_SA;HF_SA;G_SA; | Released | TA-I;RALEC;CYNTEC;YAGEO;WALSIN | RM04FTN5101 ; RTT025101FTH ; RR0510S-512-FN ; RC0402FR-075K1L;WR04X5101FTL | Multiple |  | Purchase | SMT | 2 | PCS | PR39 PR48 |
| 3 | 55.64W02.MAAG | 64.51025.6DL | CHIP RES 51K F 1/16W 0402 | R2_SA;HF_SA;G_SA; | Released | TA-I ; RALEC ; CYNTEC ; YAGEO;WALSIN | RM04FTN5102 ; RTT025102FTH ; RR0510S-513-FN ; RC0402FR-0751KL;WR04X5102FTL | Multiple |  | Purchase | SMT | 3 | PCS | PR33 PR34 PR46 |
| 3 | 55.64W02.MAAG | 64.51125.6DL | CHIP RES 51.1K F 1/16W 0402 | R2_SA;HF_SA;G_SA; | Released | TA-I;RALEC;CYNTEC;YAGEO;WALSIN | RM04FTN5112;RTT025112FTH;RR0510S-5112-FN;RC0402FR-0751K1L;WR04X5112FTL | Multiple |  | Purchase | SMT | 1 | PCS | PR3 |
| 3 | 55.64W02.MAAG | 64.54925.6DL | CHIP RES 54.9K F 1/16W 0402 | R2_SA;HF_SA;G_SA; | Released | TA-I ; RALEC ; CYNTEC ; YAGEO | RM04FTN5492 ; RTT025492FTH ; RR0510S-5492-FN ; RC0402FR-0754K9L | Multiple |  | Purchase | SMT | 1 | PCS | PR40 |
| 3 | 55.64W02.MAAG | 64.68115.6DL | CHIP RES 6.81K F 1/16W 0402 | R2_SA;HF_SA;G_SA; | Released | TAI;RALEC;CYNTEC;YAGEO | RM04FTN6811;RTT026811FTH;RR0510S-6811-FN; RC0402FR-076K81L | Multiple |  | Purchase | SMT | 4 | PCS | PR108 PR109 PR112 PR113 |
| 3 | 55.64W02.MAAG | 64.R0025.97L | CHIP RES 0.002 F 2W 2512 | R2_SA;HF_SA;G_SA; | Released | TAI;CYNTEC;YAGEO | RLM25FEER002;RL-3264-9-R002-FN;PA2512FKF7W0R002E | Multiple |  | Purchase | SMT | 4 | PCS | PR60 PR61 PR62 PR63 |
| 3 | 55.64W02.MAAG | 68.00217.561 | CHIP BEAD FCM1608CF-121T03 | R2_SA;HF_SA;G_SA; | Released | TAITECH | FCM1608CF-121T03 | Single |  | Purchase | SMT | 2 | PCS | L1 L2 |
| 3 | 55.64W02.MAAG | 68.2201D.10J | CHIP IND 22UH #A921CY-220M=P3 | R2_SA;HF_SA; | Released | MURATA | #A921CY-220M=P3 | Single |  | Purchase | SMT | 1 | PCS | PL7 |
| 3 | 55.64W02.MAAG | 71.07904.A0G | IC H/W MONI NCT7904D LQFP 48P | R2_SA;HF_SA; | Released | NUVOTON | NCT7904D | Single |  | Purchase | SMT | 1 | PCS | U1 |
| 3 | 55.64W02.MAAG | 71.09551.A0W | IC LED BLINK PCA9551PW,118 TSSOP 16P | R2_SA;HF_SA; | Obsoleted | NXP | PCA9551PW,118 | Single |  | Purchase | SMT | 1 | PCS | U6 |
| 3 | 55.64W02.MAAG | 72.02464.00Q | IC EPROM 24LC64T-I/STG TSSOP8P | R2_SA;HF_SA; | Released | MICROCHIP | 24LC64T-I/STG | Single |  | Purchase | SMT | 1 | PCS | U5 |
| 3 | 55.64W02.MAAG | 73.01G32.AHH | IC CMOS 74LVC1G32GW,125 SC70-5 | R2_SA;HF_SA;G_SA; | Released | NXP | 74LVC1G32GW,125 | Single |  | Purchase | SMT | 3 | PCS | U10 U11 U3 |
| 3 | 55.64W02.MAAG | 73.07407.BHB | IC CMOS SN74LV07APWR TSSOP 14P | R2_SA;HF_SA; | Released | TI | SN74LV07APWR | Single |  | Purchase | SMT | 1 | PCS | U7 |
| 3 | 55.64W02.MAAG | 74.01276.B7Z | IC SWAP CTRL ADM1276-3ACPZ-RL LFCSP 20P | R2_SA;HF_SA; | Obsoleted | ADI | ADM1276-3ACPZ-RL | Single |  | Purchase | SMT | 1 | PCS | PU1 |
| 3 | 55.64W02.MAAG | 74.02490.A79 | IC PWR CTRL TPS2490DGSR MSOP10 | R2_SA;HF_SA; | Released | TI | TPS2490DGSR | Single |  | Purchase | SMT | 2 | PCS | PU6 PU7 |
| 3 | 55.64W02.MAAG | 74.07368.071 | IC PWM COMPARATOR NCT7368S SOP 8P | R2_SA;HF_SA; | Released | NUVOTON | NCT7368S | Single |  | Purchase | SMT | 1 | PCS | U2 |
| 3 | 55.64W02.MAAG | 74.08201.04P | IC DC/DC REGULATOR SY8201ABC SOT23-6 | R2_SA;HF_SA; | Released | SILERGY | SY8201ABC | Single |  | Purchase | SMT | 1 | PCS | U4 |
| 3 | 55.64W02.MAAG | 77.21561.00L | CHIP CAP POS 15U 25V 25TQC15M | R2_SA;HF_SA;G_SA; | Released | SANYO | 25TQC15M | Single |  | Purchase | SMT | 9 | PCS | TC12 TC13 TC14 TC15 TC16 TC17 TC18 TC4 TC8 |
| 3 | 55.64W02.MAAG | 78.10322.2FL | CHIP CAP C 0.01U 25V K0402 X7R | R2_SA;HF_SA;G_SA; | Released | AVX;DARFON;MURATA;PHYCOMP;SAMSUNG;TAIYO;TDK;MURATA;YAGEO | 04023C103KAT2A;C1005X7R103KFT;GRM155R71E103KA01D;223891715636;CL05B103KA5NNNC;TMK105BJ103KV-F;C1005X7R1E103KT000F;WBM155R71E103KA01D;CC0402KRX7R8BB103 | Multiple |  | Purchase | SMT | 3 | PCS | PC5 PC85 PC86 |
| 3 | 55.64W02.MAAG | 78.10324.2BL | CHIP CAP C 0.01U 50V K0603 X7R | R2_SA;HF_SA;G_SA; | Released | AVX;KEMET;MURATA;PHYCOMP;SAMSUNG;TDK;DARFON;PANASONIC;WALSIN | 06035C103KAT2A;C0603C103K5RAC;GRM188R71H103KA01D;223858615636;CL10B103KB8NNNC;C1608X7R1H103KT;C1608X7R103KGT;ECJ1VB1H103K;0603B103K500CT | Multiple |  | Purchase | SMT | 2 | PCS | PC91 PC92 |
| 3 | 55.64W02.MAAG | 78.10421.2FL | CHIP CAP C 0.1U 16V K0402 X7R | R2_SA;HF_SA;G_SA; | Released | DARFON;MURATA;PHYCOMP;SAMSUNG;TAIYO;WALSIN;YAGEO | C1005X7R104KET;GRM155R71C104KA88D;223878715649;CL05B104KO5NNNC;EMK105B7104KV-F;0402B104K160CT;CC0402KRX7R7BB104 | Multiple |  | Purchase | SMT | 4 | PCS | C2 C4 C5 PC41 |
| 3 | 55.64W02.MAAG | 78.10422.5FL | CHIP CAP C 0.1U 25V K0402 X5R | R2_SA;HF_SA;G_SA; | Released | MURATA;YAGEO;TDK;TAIYO;SAMSUNG;WALSIN;DARFON | GRM155R61E104KA87D;CC0402KRX5R8BB104;C1005X5R1E104KT000E;TMK105BJ104KV-F;CL05A104KA5NNNC;0402X104K250CT;C1005X5R104KFT | Multiple |  | Purchase | SMT | 4 | PCS | C51 C58 PC89 PC90 |
| 3 | 55.64W02.MAAG | 78.10424.2BL | CHIP CAP C 0.1U 50V K0603 X7R | R2_SA;HF_SA;G_SA; | Released | MURATA;AVX;PHYCOMP;SAMSUNG;DARFON;WALSIN;YAGEO | GRM188R71H104KA93D;06035C104KAT2A;223858615649;CL10B104KB8NNNC;C1608X7R104KGT;0603B104K500CT;CC0603KRX7R9BB104 | Multiple |  | Purchase | SMT | 17 | PCS | C10 C11 C14 C16 C20 C23 C24 C25 C31 C33 C39 C41 C47 C49 C52 C54 PC96 |
| 3 | 55.64W02.MAAG | 78.10521.2BL | CHIP CAP C 1U 16V K0603 X7R | R2_SA;HF_SA;G_SA; | Released | KEMET;MURATA;TAIYO;TDK;YAGEO;WALSIN;SAMSUNG;DARFON | C0603C105K4RAC;GRM188R71C105KA12D;EMK107B7105KA-T;C1608X7R1C105KT;CC0603KRX7R7BB105;0603B105K160CT;CL10B105KO8NNNC;C1608X7R105KET | Multiple |  | Purchase | SMT | 7 | PCS | C12 C13 C15 C19 C53 C55 C9 |
| 3 | 55.64W02.MAAG | 78.10522.21L | CHIP CAP C 1U 25V K0805 X7R | R2_SA;HF_SA;G_SA; | Released | TAIYO;TDK;MURATA;SAMSUNG;DARFON;WALSIN;YAGEO;PHYCOMP | TMK212B7105KG-T;C2012X7R1E105KT;GRM21BR71E105KA99L;CL21B105KAFNNNE;C2012X7R105KFP;0805B105K250CT;CC0805KKX7R8BB105;222291015663 | Multiple |  | Purchase | SMT | 2 | PCS | PC10 PC9 |
| 3 | 55.64W02.MAAG | 78.10522.5BL | CHIP CAP C 1U 25V K0603 X5R | R2_SA;HF_SA;G_SA; | Released | MURATA;TDK;PHYCOMP;TAIYO;MATSUKI;DARFON;TDK;WALSIN;SAMSUNG;YAGEO | GRM188R61E105KA12D;C1608X5R1E105KT000N;223891613663;TMK107BJ105KA-T;MAG03X5R1E105K;C1608X5R105KFT;C1608X5R1E105KT000N;0603X105K250CT;CL10A105KA8NNNC;CC0603KRX5R8BB105 | Multiple |  | Purchase | SMT | 11 | PCS | C257 C258 C26 C32 C34 C40 C42 C48 C50 PC1 PC4 |
| 3 | 55.64W02.MAAG | 78.10622.51L | CHIP CAP C 10U 25V K0805 X5R | R2_SA;HF_SA;G_SA; | Released | MATSUKI;SAMSUNG;TAIYO;AVX;MURATA;TDK;YAGEO;WALSIN;SAMSUNG;DARFON;TAIYO | MAG05X5R1E106K;CL21A106KAYNNNG;TMK212BJ106KG-TD;CM21X5R106K25AT;GRM21BR61E106KA73L;C2012X5R1E106KT;CC0805KKX5R8BB106;0805X106K250CT;CL21A106KAYNNNE;C2012X5R106KFP;TMK212BBJ106KG-T | Multiple |  | Purchase | SMT | 4 | PCS | C1 C3 PC2 PC95 |
| 3 | 55.64W02.MAAG | 78.10622.52L | CHIP CAP C 10U 25V K1206 X5R | R2_SA;HF_SA;G_SA; | Released | TAIYO;MURATA;AVX;TDK;KEMET;MATSUKI;PHYCOMP;DARFON;SAMSUNG;WALSIN;YAGEO | TMK316BJ106KL-T;GRM31CR61E106KA12L;12063D106KAT2A;C3216X5R1E106KT;C1206C106K3PAC;MAG06X5R1E106K;222291113676;C3216X5R106KFP;CL31A106KAHNNNE;1206X106K250CT;CC1206KKX5R8BB106 | Multiple |  | Purchase | SMT | 1 | PCS | C259 |
| 3 | 55.64W02.MAAG | 78.22034.1BL | CHIP CAP 22P50V J0603 NPO(ROHS | R2_SA;HF_SA;G_SA; | Released | PHYCOMP;MURATA;AVX;TDK;SAMSUNG;DARFON;WALSIN | 223886715229;GRM1885C1H220JA01D;06035A220JAT2A;C1608C0G1H220JT;CL10C220JB8NNNC;C1608NPO220JGT;0603N220J500LT | Multiple |  | Purchase | SMT | 1 | PCS | PC42 |
| 3 | 55.64W02.MAAG | 78.22124.2FL | CHIP CAP C 220P 50V K0402 X7R | R2_SA;HF_SA;G_SA; | Released | MURATA;AVX;TAIYO;PHYCOMP;DARFON;WALSIN;YAGEO | GRM155R71H221KA01D;04025C221KAT2A;UMK105B7221KV-F;223858715614;C1005X7R221KGT;0402B221K500CT;CC0402KRX7R9BB221 | Multiple |  | Purchase | SMT | 4 | PCS | PC87 PC88 PC93 PC94 |
| 3 | 55.64W02.MAAG | 78.22224.2FL | CHIP CAP C 2200P 50V K0402 X7R | R2_SA;HF_SA;G_SA; | Released | MURATA;AVX;TAIYO;PHYCOMP;DARFON;SAMSUNG;WALSIN;YAGEO | GRM155R71H222KA01D;04025C222KAT2A;UMK105B7222KV-F;223858715627;C1005X7R222KGT;CL05B222KB5NNNC;0402B222K500CT;CC0402KRX7R9BB222 | Multiple |  | Purchase | SMT | 2 | PCS | C7 C8 |
| 3 | 55.64W02.MAAG | 78.22324.2BL | CHIP CAP C .022U 50V K0603 X7R | R2_SA;HF_SA;G_SA; | Released | MURATA;PHYCOMP;SAMSUNG;TDK;DARFON | GRM188R71H223KA01D;223858615641;CL10B223KB8NNNC;C1608X7R1H223KT;C1608X7R223KGT | Multiple |  | Purchase | SMT | 1 | PCS | PC6 |
| 3 | 55.64W02.MAAG | 78.22611.52L | CHIP CAP 22U 16V M1206 X5R | R2_SA;HF_SA;G_SA; | Released | MURATA;TAIYO;AVX;SAMSUNG;DARFON | GRM31CR61C226ME15L;EMK316BJ226ML-T;CM316X5R226M16AT;CL31A226MOHNNNE;C3216X5R226MEP | Multiple |  | Purchase | SMT | 1 | PCS | PC43 |
| 3 | 55.64W02.MAAG | 78.47510.5FL | CHIP CAP C 4.7U 6.3V M0402 X5R | R2_SA;HF_SA;G_SA; | Released | SAMSUNG;TAIYO;MURATA;AVX;YAGEO;WALSIN;DARFON;TDK | CL05A475MQ5NRNC;JDK105BJ475MV-F;GRM155R60J475ME87D;CV05X5R475M06AH065;CC0402MRX5R5BB475;0402X475M6R3CT;C1005X5R475MCT;C1005X5R0J475KT | Multiple |  | Purchase | SMT | 1 | PCS | C6 |
| 3 | 55.64W02.MAAG | 78.47524.L2L | CHIP CAP C 4.7UF 50V K1206 X5R T=0.9 | R2_SA;HF_SA;G_SA; | Released | MURATA;SAMSUNG;TAIYO | GRM319R61H475KA12D;CL31A475KB9LNNC;UMK316BJ475KD-T | Multiple |  | Purchase | SMT | 1 | PCS | PC40 |
| 3 | 55.64W02.MAAG | 82.20034.191 | OSC 33M 3.3V 50PPM HXO-56B SMD | R2_SA;HF_SA; | Released | HOSONIC | D56B33.0000MNS | Single |  | Purchase | SMT | 1 | PCS | OSC1 |
| 3 | 55.64W02.MAAG | 83.00015.0AD | DIODE TVS SMCJ15A-13-F SMC | R2_SA;HF_SA; | Released | DIODES | SMCJ15A-13-F | Single |  | Purchase | SMT | 1 | PCS | PD2 |
| 3 | 55.64W02.MAAG | 83.00016.A1H | DIODE SW BAS16H,115 100VSOD123F | R2_SA;HF_SA;G_SA; | Released | NEXPERIA | BAS16H,115 | Single |  | Purchase | SMT | 12 | PCS | D1 D10 D11 D12 D2 D3 D4 D5 D6 D7 D8 D9 |
| 3 | 55.64W02.MAAG | 83.1S380.01F | DIODE SW 1SS380TE-17 SOD-323 | R2_SA; | Released | ROHM | 1SS380TE-17 | Single |  | Purchase | SMT | 1 | PCS | D19 |
| 3 | 55.64W02.MAAG | 83.3R004.B8D | DIODE S.B MBRS340T3G 40V3A SMC | R2_SA;HF_SA; | Released | ON | MBRS340T3G | Single |  | Purchase | SMT | 3 | PCS | D14 D15 D16 |
| 3 | 55.64W02.MAAG | 83.R0304.B3F | DIODE CH751H-40PT 40V0.03A | R2_SA; | Obsoleted | CHENMKO | CH751H-40PT | Single |  | Purchase | SMT | 1 | PCS | D18 |
| 3 | 55.64W02.MAAG | 84.03904.L06 | XTOR PMBS3904,215 NPN SOT23 (GP) | R2_SA;HF_SA;G_SA; | Released | NEXPERIA | PMBS3904,215 | Multiple |  | Purchase | SMT | 11 | PCS | PQ14 PQ5 PQ6 Q1 Q2 Q3 Q4 Q5 Q6 Q7 Q8 |
| 3 | 55.64W02.MAAG | 84.03906.R11 | XTOR MMBT3906 PNP SOT-23 | R2_SA;HF_SA;G_SA; | Released | PANJIT | MMBT3906 | Single |  | Purchase | SMT | 1 | PCS | PQ4 |
| 3 | 55.64W02.MAAG | 84.27002.C3F | FET MOS 2N7002DW-7-F NC SOT363 | R2_SA;HF_SA; | Obsoleted | DIODES | 2N7002DW-7-F | Single |  | Purchase | SMT | 1 | PCS | Q10 |
| 3 | 55.64W02.MAAG | 84.27002.W31 | FET MOS 2N7002 NC SOT-23 | R2_SA;HF_SA;G_SA; | Released | PANJIT | 2N7002 | Single |  | Purchase | SMT | 1 | PCS | Q49 |
| 2 | 55.64W02.A91G | 86.00Q43.140 | SCRW NUT HEX M3 | R2_SA;HF_SA;G_SA; | Released | TBD |  | Single |  | Purchase | DIP | 4 | PCS |  |
| 2 | 55.64W02.A91G | 86.1A524.100 | SCRW MACH PAN M3*10L | R2_SA;HF_SA; | Released | TBD |  | Single |  | Purchase | DIP | 4 | PCS |  |
| 1 | 91.64W10.A57G | DP.64W10.A03 | PACKING FOR KNOX FAN CONTROLLER BOARD | R2; | Released |  |  |  | M | Manufacture |  | 1 | PCS |  |
| 2 | DP.64W10.A03 | 38.09008.001 | DESICANT SILICA GEL 30G H25 | R2_SA;HF_SA; | Released | TBD |  | Single |  | Purchase |  | 1 | PCS |  |
| 2 | DP.64W10.A03 | 40.54T01.001 | LBL CAUTION FOR P97AE | R2_SA;HF_SA;G_SA; | Released | CHENGMAY | 40.54T01.001 | Single |  | Purchase |  | 1 | PCS |  |
| 2 | DP.64W10.A03 | 42.5I405.001 | BAG PE ESD 140*550MM | R2_SA;HF_SA; | Released | TBD |  | Single |  | Purchase |  | 1 | PCS |  |
| 2 | DP.64W10.A03 | 42.60X01.001 | BAG ZIP 320*230MM | R2_SA;HF_SA; | Released | HONGWANG;WINGFUNG | 42.60X01.001 | Multiple |  | Purchase |  | 3.1E-2 | PCS |  |
| 2 | DP.64W10.A03 | 44.5P305.011 | CTN AB B/R 490*390*554MM | R2_SA;HF_SA; | Released | TBD |  | Single |  | Purchase |  | 3.1300000000000001E-2 | PCS |  |
| 2 | DP.64W10.A03 | 45.00005.312 | LBL CTN ART 124*40 B/W ALL | R2_SA;HF_SA;G_SA; | Released | CHENGMAY | 45.00005.312 | Single |  | Purchase |  | 3.1E-2 | PCS |  |
| 2 | DP.64W10.A03 | 45.3B201.001 | LBL CTN 101.6X152.4 H100-ASTRO | R2_SA;HF_SA; | Released | ZHENFENG |  | Single |  | Purchase |  | 3.1300000000000001E-2 | PCS |  |
| 2 | DP.64W10.A03 | 46.30S02.001 | CORNER KRAFT PAPER 900*50*50*3 | R2_SA;HF_SA;G_SA; | Released | KHL;SAFEWAY | 46.30S02.001 | Multiple |  | Purchase |  | 3.5000000000000001E-3 | PCS |  |
| 2 | DP.64W10.A03 | 46.58F01.001 | CORNER PAPER1100*50*50*3 ORIGI | R2_SA;HF_SA; | Released | COPLASCO;MYS | 46.58F01.001 | Multiple |  | Purchase |  | 3.5000000000000001E-3 | PCS |  |
| 2 | DP.64W10.A03 | 46.60A03.001 | SHEET AB FLUTE 1200*1000 NS110 | R2_SA;HF_SA;G_SA; | Released | GINYOUNG;TRICAN | 46.60A03.001 | Multiple |  | Purchase |  | 1.8E-3 | PCS |  |
| 2 | DP.64W10.A03 | 46.67E01.001 | CORNER PAPER 1520*50*50*5MM | R2_SA;HF_SA; | Released | TBD |  | Single |  | Purchase |  | 7.0000000000000001E-3 | PCS |  |
| 2 | DP.64W10.A03 | 46.7A301.001 | AIR-BAG ALL 1800MM X 1000MM | R2_SA;HF_SA;G_SA; | Released | TBD |  | Single |  | Purchase |  | 1.6000000000000001E-3 | PCS |  |
| 2 | DP.64W10.A03 | 47.54Z11.001 | CSN PAD EPE 475*375*15MM | R2_SA;HF_SA; | Released | TRICAN | Void | Single |  | Purchase |  | 6.25E-2 | PCS |  |
| 2 | DP.64W10.A03 | 47.57S22.001 | PALLET PLYWOOD 1200*1000*114MM | R2_SA;HF_SA; | Released | JIAMAO | Void | Single |  | Purchase |  | 1.8E-3 | PCS |  |
| 2 | DP.64W10.A03 | 47.5I308.001 | P-PAD AB 479*50MM | R2_SA;HF_SA; | Released | TBD |  | Single |  | Purchase |  | 6.25E-2 | PCS |  |
| 2 | DP.64W10.A03 | 47.5I510.001 | P-PAD AB 380*58MM | R2_SA;HF_SA; | Released | TBD |  | Single |  | Purchase |  | 6.25E-2 | PCS |  |
| 2 | DP.64W10.A03 | 47.5P333.001 | PARTITION A 479*506MM | R2_SA;HF_SA; | Released | TBD |  | Single |  | Purchase |  | 0.15629999999999999 | PCS |  |
| 2 | DP.64W10.A03 | 47.64W05.001 | CSN PARTITION A 506*375MM | R2_SA;HF_SA; | Released | TBD |  | Single |  | Purchase |  | 0.28129999999999999 | PCS |  |
| Level | Parent Number | Part Number | Description | Green Factor | Life Cycle State | Manufacturer | Manufacturer Part Number | Source | BOM Usage | M/P Code | S/D | Qty | UoM | Location |
